#ISCELL
  pure_quanta quanta_title_block_c *
  *
#CELL
  pure_quanta q_cap *
  page79_i1
#CELL
  pure_quanta q_cap *
  page79_i10
#CELL
  pure_quanta q_cap *
  page79_i11
#CELL
  pure_quanta q_cap *
  page79_i12
#CELL
  pure_quanta q_cap *
  page79_i13
#ISCELL
  logical_power universal_power *
  page79_i14
#CELL
  pure_quanta q_cap *
  page79_i15
#CELL
  pure_quanta q_cap *
  page79_i16
#CELL
  pure_quanta q_cap *
  page79_i17
#ISCELL
  logical_power universal_power *
  page79_i18
#CELL
  pure_quanta q_cap *
  page79_i19
#ISCELL
  logical_power universal_power *
  page79_i2
#CELL
  pure_quanta q_cap *
  page79_i20
#CELL
  pure_quanta q_cap *
  page79_i21
#ISCELL
  logical_power universal_power *
  page79_i22
#CELL
  pure_quanta q_cap *
  page79_i23
#CELL
  pure_quanta q_cap *
  page79_i24
#CELL
  pure_quanta q_cap *
  page79_i25
#CELL
  pure_quanta q_cap *
  page79_i26
#CELL
  pure_quanta q_cap *
  page79_i27
#ISCELL
  logical_power universal_gnd *
  page79_i28
#CELL
  pure_quanta q_cap *
  page79_i29
#CELL
  pure_quanta q_cap *
  page79_i3
#ISCELL
  logical_power universal_gnd *
  page79_i30
#CELL
  pure_quanta q_cap *
  page79_i31
#CELL
  pure_quanta q_cap *
  page79_i32
#CELL
  pure_quanta q_cap *
  page79_i33
#CELL
  pure_quanta q_cap *
  page79_i34
#CELL
  pure_quanta q_cap *
  page79_i35
#ISCELL
  logical_power universal_power *
  page79_i36
#CELL
  pure_quanta q_cap *
  page79_i37
#CELL
  pure_quanta q_cap *
  page79_i38
#CELL
  pure_quanta q_cap *
  page79_i39
#CELL
  pure_quanta q_cap *
  page79_i4
#ISCELL
  logical_power universal_gnd *
  page79_i40
#CELL
  pure_quanta q_cap *
  page79_i41
#CELL
  pure_quanta q_cap *
  page79_i42
#CELL
  pure_quanta q_cap *
  page79_i43
#CELL
  pure_quanta q_cap *
  page79_i44
#ISCELL
  logical_power universal_power *
  page79_i45
#CELL
  pure_quanta q_cap *
  page79_i46
#CELL
  pure_quanta q_cap *
  page79_i47
#ISCELL
  logical_power universal_gnd *
  page79_i48
#CELL
  pure_quanta q_cap *
  page79_i49
#CELL
  pure_quanta q_cap *
  page79_i5
#CELL
  pure_quanta q_cap *
  page79_i50
#CELL
  pure_quanta q_cap *
  page79_i51
#CELL
  pure_quanta q_cap *
  page79_i52
#CELL
  pure_quanta q_cap *
  page79_i53
#ISCELL
  logical_power universal_gnd *
  page79_i54
#CELL
  pure_quanta q_cap *
  page79_i55
#ISCELL
  logical_power universal_gnd *
  page79_i6
#CELL
  pure_quanta q_cap *
  page79_i7
#CELL
  pure_quanta q_cap *
  page79_i8
#CELL
  pure_quanta q_cap *
  page79_i9
